#ISCELL
  pure_quanta quanta_title_block_c *
  *
#CELL
  pure_quanta me_dummy_symbol *
  page290_i10
#CELL
  pure_quanta me_dummy_symbol *
  page290_i11
#CELL
  pure_quanta me_dummy_symbol *
  page290_i12
#CELL
  pure_quanta me_dummy_symbol *
  page290_i13
#CELL
  pure_quanta me_dummy_symbol *
  page290_i14
#CELL
  pure_quanta me_dummy_symbol *
  page290_i15
#CELL
  pure_quanta me_dummy_symbol *
  page290_i16
#CELL
  pure_quanta dummy_symbol *
  page290_i17
#CELL
  pure_quanta me_dummy_symbol *
  page290_i18
#CELL
  pure_quanta me_dummy_symbol *
  page290_i19
#CELL
  pure_quanta dummy_symbol *
  page290_i23
#CELL
  pure_quanta tp *
  page290_i40
#CELL
  pure_quanta tp *
  page290_i41
#CELL
  pure_quanta tp *
  page290_i42
#CELL
  pure_quanta tp *
  page290_i43
#CELL
  pure_quanta tp *
  page290_i45
#CELL
  pure_quanta tp *
  page290_i47
#CELL
  pure_quanta me_dummy_symbol *
  page290_i62
#CELL
  pure_quanta me_dummy_symbol *
  page290_i63
#CELL
  pure_quanta me_dummy_symbol *
  page290_i64
#CELL
  pure_quanta me_dummy_symbol *
  page290_i65
#CELL
  pure_quanta tp *
  page290_i69
#CELL
  pure_quanta tp *
  page290_i70
#CELL
  pure_quanta tp *
  page290_i71
#CELL
  pure_quanta tp *
  page290_i72
#CELL
  pure_quanta me_dummy_symbol *
  page290_i73
#CELL
  pure_quanta me_dummy_symbol *
  page290_i74
#CELL
  pure_quanta me_dummy_symbol *
  page290_i75
#CELL
  pure_quanta me_dummy_symbol *
  page290_i76
#CELL
  pure_quanta me_dummy_symbol *
  page290_i9
